(kicad_pcb
	(version 20260206)
	(generator "pcbnew")
	(generator_version "10.0")
	(general
		(thickness 1.6)
		(legacy_teardrops no)
	)
	(paper "A4")
	(title_block
		(title "Wiwynn_Tioga_Pass_MB.brd")
		(comment 1 "Tioga Pass / footprints 894-894 of 4770")
	)
	(layers
		(0 "F.Cu" signal "TOP")
		(4 "In1.Cu" signal "L2GND")
		(6 "In2.Cu" signal "L3")
		(8 "In3.Cu" signal "L4GND")
		(10 "In4.Cu" signal "L5")
		(12 "In5.Cu" signal "L6GND")
		(14 "In6.Cu" signal "L7VCC")
		(16 "In7.Cu" signal "L8VCC")
		(18 "In8.Cu" signal "L9GND")
		(20 "In9.Cu" signal "L10")
		(22 "In10.Cu" signal "L11GND")
		(24 "In11.Cu" signal "L12")
		(26 "In12.Cu" signal "L13GND")
		(2 "B.Cu" signal "BOTTOM")
		(9 "F.Adhes" user "F.Adhesive")
		(11 "B.Adhes" user "B.Adhesive")
		(13 "F.Paste" user "Package Geometry/Pastemask Top")
		(15 "B.Paste" user "Package Geometry/Pastemask Bottom")
		(5 "F.SilkS" user "Ref Des/Silkscreen Top")
		(7 "B.SilkS" user "Ref Des/Silkscreen Bottom")
		(1 "F.Mask" user "Board Geometry/Soldermask Top")
		(3 "B.Mask" user "Board Geometry/Soldermask Bottom")
		(17 "Dwgs.User" user "User.Drawings")
		(19 "Cmts.User" user "User.Comments")
		(21 "Eco1.User" user "User.Eco1")
		(23 "Eco2.User" user "User.Eco2")
		(25 "Edge.Cuts" user "Board Geometry/Outline")
		(27 "Margin" user)
		(31 "F.CrtYd" user "Package Geometry/Place Bound Top")
		(29 "B.CrtYd" user "Package Geometry/Place Bound Bottom")
		(35 "F.Fab" user "Ref Des/Assembly Top")
		(33 "B.Fab" user "Ref Des/Assembly Bottom")
	)
	(footprint ""
		(layer "F.Cu")
		(at 388.072376 -30.520894 90)
		(property "Reference" "J8F1"
			(at 0 0 90)
			(layer "F.SilkS")
			(hide yes)
			(effects
				(font
					(size 1.27 1.27)
				)
			)
		)
		(property "Value" "*"
			(at 12.319 -1.3335 90)
			(unlocked yes)
			(layer "F.Fab")
			(hide yes)
			(effects
				(font
					(size 1.27 1.016)
					(thickness 0.1524)
				)
			)
		)
		(property "Device Type" "SKT-MINI67P-41-GP_SOCKET-G4-SKA"
			(at 12.319 -2.8575 90)
			(unlocked yes)
			(layer "F.Fab")
			(hide yes)
			(effects
				(font
					(size 1.27 1.016)
					(thickness 0.1524)
				)
			)
		)
		(duplicate_pad_numbers_are_jumpers no)
		(fp_line
			(start -9.4234 -6.3881)
			(end -9.0678 -6.3881)
			(stroke
				(width 0.3302)
				(type default)
			)
			(layer "F.SilkS")
		)
		(fp_line
			(start 11.2014 -6.2992)
			(end 11.2014 3.302)
			(stroke
				(width 0.1524)
				(type default)
			)
			(layer "F.SilkS")
		)
		(fp_line
			(start -11.2014 -6.2992)
			(end 11.2014 -6.2992)
			(stroke
				(width 0.1524)
				(type default)
			)
			(layer "F.SilkS")
		)
		(fp_line
			(start 11.2014 3.302)
			(end -11.2014 3.302)
			(stroke
				(width 0.1524)
				(type default)
			)
			(layer "F.SilkS")
		)
		(fp_line
			(start -11.2014 3.302)
			(end -11.2014 -6.2992)
			(stroke
				(width 0.1524)
				(type default)
			)
			(layer "F.SilkS")
		)
		(fp_poly
			(pts
				(xy -9.218168 -6.38175) (xy -8.583168 -7.01675) (xy -9.853168 -7.01675)
			)
			(stroke
				(width 0)
				(type default)
			)
			(fill yes)
			(layer "F.SilkS")
		)
		(fp_rect
			(start -10.9474 2.7051)
			(end 10.9474 -5.7023)
			(stroke
				(width 0)
				(type default)
			)
			(fill no)
			(layer "F.CrtYd")
		)
		(fp_poly
			(pts
				(xy -11.4554 3.556) (xy -11.4554 -6.5532) (xy 11.4554 -6.5532) (xy 11.4554 3.556) (xy 0.508 3.556)
				(xy 0.508 2.7051) (xy 10.9474 2.7051) (xy 10.9474 -5.7023) (xy -10.9474 -5.7023) (xy -10.9474 2.7051)
				(xy 0.4953 2.7051) (xy 0.4953 3.556)
			)
			(stroke
				(width 0)
				(type default)
			)
			(fill no)
			(layer "F.CrtYd")
		)
		(fp_rect
			(start -11.4554 3.556)
			(end 11.4554 -6.5532)
			(stroke
				(width 0)
				(type default)
			)
			(fill no)
			(layer "F.Fab")
		)
		(pad "" np_thru_hole circle
			(at -9.99998 0 90)
			(size 0.254 0.254)
			(drill 1.1176)
			(layers "*.Cu" "*.Mask")
			(clearance 0.7874)
			(thermal_gap 0.7874)
		)
		(pad "" np_thru_hole circle
			(at 9.99998 0 90)
			(size 0.254 0.254)
			(drill 1.6002)
			(layers "*.Cu" "*.Mask")
			(clearance 1.0287)
			(thermal_gap 1.0287)
		)
		(pad "1" smd rect
			(at -9.249918 -5.275072 90)
			(size 0.3048 1.5494)
			(layers "F.Cu" "F.Mask" "F.Paste")
			(net "GND")
		)
		(pad "2" smd rect
			(at -8.999982 2.275078 90)
			(size 0.3048 1.5494)
			(layers "F.Cu" "F.Mask" "F.Paste")
			(net "P3V3")
		)
		(pad "3" smd rect
			(at -8.750046 -5.275072 90)
			(size 0.3048 1.5494)
			(layers "F.Cu" "F.Mask" "F.Paste")
			(net "GND")
		)
		(pad "4" smd rect
			(at -8.50011 2.275078 90)
			(size 0.3048 1.5494)
			(layers "F.Cu" "F.Mask" "F.Paste")
			(net "P3V3")
		)
		(pad "5" smd rect
			(at -8.24992 -5.275072 90)
			(size 0.3048 1.5494)
			(layers "F.Cu" "F.Mask" "F.Paste")
			(net "P3E_PCH_M2_RX_DN<3>")
		)
		(pad "6" smd rect
			(at -7.999984 2.275078 90)
			(size 0.3048 1.5494)
			(layers "F.Cu" "F.Mask" "F.Paste")
			(net "NC_M2<0>")
		)
		(pad "7" smd rect
			(at -7.750048 -5.275072 90)
			(size 0.3048 1.5494)
			(layers "F.Cu" "F.Mask" "F.Paste")
			(net "P3E_PCH_M2_RX_DP<3>")
		)
		(pad "8" smd rect
			(at -7.500112 2.275078 90)
			(size 0.3048 1.5494)
			(layers "F.Cu" "F.Mask" "F.Paste")
			(net "NC_M2<1>")
		)
		(pad "9" smd rect
			(at -7.249922 -5.275072 90)
			(size 0.3048 1.5494)
			(layers "F.Cu" "F.Mask" "F.Paste")
			(net "GND")
		)
		(pad "10" smd rect
			(at -6.999986 2.275078 90)
			(size 0.3048 1.5494)
			(layers "F.Cu" "F.Mask" "F.Paste")
			(net "TP_LED_M2_ACT_N")
		)
		(pad "11" smd rect
			(at -6.75005 -5.275072 90)
			(size 0.3048 1.5494)
			(layers "F.Cu" "F.Mask" "F.Paste")
			(net "P3E_PCH_M2_TX_C_DN<3>")
		)
		(pad "12" smd rect
			(at -6.500114 2.275078 90)
			(size 0.3048 1.5494)
			(layers "F.Cu" "F.Mask" "F.Paste")
			(net "P3V3")
		)
		(pad "13" smd rect
			(at -6.249924 -5.275072 90)
			(size 0.3048 1.5494)
			(layers "F.Cu" "F.Mask" "F.Paste")
			(net "P3E_PCH_M2_TX_C_DP<3>")
		)
		(pad "14" smd rect
			(at -5.999988 2.275078 90)
			(size 0.3048 1.5494)
			(layers "F.Cu" "F.Mask" "F.Paste")
			(net "P3V3")
		)
		(pad "15" smd rect
			(at -5.750052 -5.275072 90)
			(size 0.3048 1.5494)
			(layers "F.Cu" "F.Mask" "F.Paste")
			(net "GND")
		)
		(pad "16" smd rect
			(at -5.500116 2.275078 90)
			(size 0.3048 1.5494)
			(layers "F.Cu" "F.Mask" "F.Paste")
			(net "P3V3")
		)
		(pad "17" smd rect
			(at -5.249926 -5.275072 90)
			(size 0.3048 1.5494)
			(layers "F.Cu" "F.Mask" "F.Paste")
			(net "P3E_PCH_M2_RX_DN<2>")
		)
		(pad "18" smd rect
			(at -4.99999 2.275078 90)
			(size 0.3048 1.5494)
			(layers "F.Cu" "F.Mask" "F.Paste")
			(net "P3V3")
		)
		(pad "19" smd rect
			(at -4.750054 -5.275072 90)
			(size 0.3048 1.5494)
			(layers "F.Cu" "F.Mask" "F.Paste")
			(net "P3E_PCH_M2_RX_DP<2>")
		)
		(pad "20" smd rect
			(at -4.500118 2.275078 90)
			(size 0.3048 1.5494)
			(layers "F.Cu" "F.Mask" "F.Paste")
			(net "Net_317")
		)
		(pad "21" smd rect
			(at -4.249928 -5.275072 90)
			(size 0.3048 1.5494)
			(layers "F.Cu" "F.Mask" "F.Paste")
			(net "GND")
		)
		(pad "22" smd rect
			(at -3.999992 2.275078 90)
			(size 0.3048 1.5494)
			(layers "F.Cu" "F.Mask" "F.Paste")
			(net "Net_318")
		)
		(pad "23" smd rect
			(at -3.750056 -5.275072 90)
			(size 0.3048 1.5494)
			(layers "F.Cu" "F.Mask" "F.Paste")
			(net "P3E_PCH_M2_TX_C_DN<2>")
		)
		(pad "24" smd rect
			(at -3.50012 2.275078 90)
			(size 0.3048 1.5494)
			(layers "F.Cu" "F.Mask" "F.Paste")
			(net "Net_319")
		)
		(pad "25" smd rect
			(at -3.24993 -5.275072 90)
			(size 0.3048 1.5494)
			(layers "F.Cu" "F.Mask" "F.Paste")
			(net "P3E_PCH_M2_TX_C_DP<2>")
		)
		(pad "26" smd rect
			(at -2.999994 2.275078 90)
			(size 0.3048 1.5494)
			(layers "F.Cu" "F.Mask" "F.Paste")
			(net "Net_320")
		)
		(pad "27" smd rect
			(at -2.750058 -5.275072 90)
			(size 0.3048 1.5494)
			(layers "F.Cu" "F.Mask" "F.Paste")
			(net "GND")
		)
		(pad "28" smd rect
			(at -2.500122 2.275078 90)
			(size 0.3048 1.5494)
			(layers "F.Cu" "F.Mask" "F.Paste")
			(net "Net_321")
		)
		(pad "29" smd rect
			(at -2.249932 -5.275072 90)
			(size 0.3048 1.5494)
			(layers "F.Cu" "F.Mask" "F.Paste")
			(net "P3E_PCH_M2_RX_DN<1>")
		)
		(pad "30" smd rect
			(at -1.999996 2.275078 90)
			(size 0.3048 1.5494)
			(layers "F.Cu" "F.Mask" "F.Paste")
			(net "Net_322")
		)
		(pad "31" smd rect
			(at -1.75006 -5.275072 90)
			(size 0.3048 1.5494)
			(layers "F.Cu" "F.Mask" "F.Paste")
			(net "P3E_PCH_M2_RX_DP<1>")
		)
		(pad "32" smd rect
			(at -1.500124 2.275078 90)
			(size 0.3048 1.5494)
			(layers "F.Cu" "F.Mask" "F.Paste")
			(net "Net_323")
		)
		(pad "33" smd rect
			(at -1.249934 -5.275072 90)
			(size 0.3048 1.5494)
			(layers "F.Cu" "F.Mask" "F.Paste")
			(net "GND")
		)
		(pad "34" smd rect
			(at -0.999998 2.275078 90)
			(size 0.3048 1.5494)
			(layers "F.Cu" "F.Mask" "F.Paste")
			(net "Net_324")
		)
		(pad "35" smd rect
			(at -0.750062 -5.275072 90)
			(size 0.3048 1.5494)
			(layers "F.Cu" "F.Mask" "F.Paste")
			(net "P3E_PCH_M2_TX_C_DN<1>")
		)
		(pad "36" smd rect
			(at -0.500126 2.275078 90)
			(size 0.3048 1.5494)
			(layers "F.Cu" "F.Mask" "F.Paste")
			(net "Net_325")
		)
		(pad "37" smd rect
			(at -0.249936 -5.275072 90)
			(size 0.3048 1.5494)
			(layers "F.Cu" "F.Mask" "F.Paste")
			(net "P3E_PCH_M2_TX_C_DP<1>")
		)
		(pad "38" smd rect
			(at 0 2.275078 90)
			(size 0.3048 1.5494)
			(layers "F.Cu" "F.Mask" "F.Paste")
			(net "TP_M2_DEVSLP")
		)
		(pad "39" smd rect
			(at 0.249936 -5.275072 90)
			(size 0.3048 1.5494)
			(layers "F.Cu" "F.Mask" "F.Paste")
			(net "GND")
		)
		(pad "40" smd rect
			(at 0.500126 2.275078 90)
			(size 0.3048 1.5494)
			(layers "F.Cu" "F.Mask" "F.Paste")
			(net "SMB_M2_SCL")
		)
		(pad "41" smd rect
			(at 0.750062 -5.275072 90)
			(size 0.3048 1.5494)
			(layers "F.Cu" "F.Mask" "F.Paste")
			(net "P3E_PCH_M2_SATA6G_RX_R_DP")
		)
		(pad "42" smd rect
			(at 0.999998 2.275078 90)
			(size 0.3048 1.5494)
			(layers "F.Cu" "F.Mask" "F.Paste")
			(net "SMB_M2_SDA")
		)
		(pad "43" smd rect
			(at 1.249934 -5.275072 90)
			(size 0.3048 1.5494)
			(layers "F.Cu" "F.Mask" "F.Paste")
			(net "P3E_PCH_M2_SATA6G_RX_R_DN")
		)
		(pad "44" smd rect
			(at 1.500124 2.275078 90)
			(size 0.3048 1.5494)
			(layers "F.Cu" "F.Mask" "F.Paste")
			(net "SMB_M2_ALT_N")
		)
		(pad "45" smd rect
			(at 1.75006 -5.275072 90)
			(size 0.3048 1.5494)
			(layers "F.Cu" "F.Mask" "F.Paste")
			(net "GND")
		)
		(pad "46" smd rect
			(at 1.999996 2.275078 90)
			(size 0.3048 1.5494)
			(layers "F.Cu" "F.Mask" "F.Paste")
			(net "Net_326")
		)
		(pad "47" smd rect
			(at 2.249932 -5.275072 90)
			(size 0.3048 1.5494)
			(layers "F.Cu" "F.Mask" "F.Paste")
			(net "P3E_PCH_M2_SATA6G_TX_R_DN")
		)
		(pad "48" smd rect
			(at 2.500122 2.275078 90)
			(size 0.3048 1.5494)
			(layers "F.Cu" "F.Mask" "F.Paste")
			(net "Net_327")
		)
		(pad "49" smd rect
			(at 2.750058 -5.275072 90)
			(size 0.3048 1.5494)
			(layers "F.Cu" "F.Mask" "F.Paste")
			(net "P3E_PCH_M2_SATA6G_TX_R_DP")
		)
		(pad "50" smd rect
			(at 2.999994 2.275078 90)
			(size 0.3048 1.5494)
			(layers "F.Cu" "F.Mask" "F.Paste")
			(net "RST_PCIE_M2_DEV_IC_N")
		)
		(pad "51" smd rect
			(at 3.24993 -5.275072 90)
			(size 0.3048 1.5494)
			(layers "F.Cu" "F.Mask" "F.Paste")
			(net "GND")
		)
		(pad "52" smd rect
			(at 3.50012 2.275078 90)
			(size 0.3048 1.5494)
			(layers "F.Cu" "F.Mask" "F.Paste")
			(net "PU_M2_CLK_REQ_N")
		)
		(pad "53" smd rect
			(at 3.750056 -5.275072 90)
			(size 0.3048 1.5494)
			(layers "F.Cu" "F.Mask" "F.Paste")
			(net "CLK_100M_M2_DN")
		)
		(pad "54" smd rect
			(at 3.999992 2.275078 90)
			(size 0.3048 1.5494)
			(layers "F.Cu" "F.Mask" "F.Paste")
			(net "FM_PE_M2_WAKE_N")
		)
		(pad "55" smd rect
			(at 4.249928 -5.275072 90)
			(size 0.3048 1.5494)
			(layers "F.Cu" "F.Mask" "F.Paste")
			(net "CLK_100M_M2_DP")
		)
		(pad "56" smd rect
			(at 4.500118 2.275078 90)
			(size 0.3048 1.5494)
			(layers "F.Cu" "F.Mask" "F.Paste")
			(net "Net_328")
		)
		(pad "57" smd rect
			(at 4.750054 -5.275072 90)
			(size 0.3048 1.5494)
			(layers "F.Cu" "F.Mask" "F.Paste")
			(net "GND")
		)
		(pad "58" smd rect
			(at 4.99999 2.275078 90)
			(size 0.3048 1.5494)
			(layers "F.Cu" "F.Mask" "F.Paste")
			(net "Net_329")
		)
		(pad "67" smd rect
			(at 7.249922 -5.275072 90)
			(size 0.3048 1.5494)
			(layers "F.Cu" "F.Mask" "F.Paste")
			(net "Net_330")
		)
		(pad "68" smd rect
			(at 7.500112 2.275078 90)
			(size 0.3048 1.5494)
			(layers "F.Cu" "F.Mask" "F.Paste")
			(net "TP_M2_32M_SUSCLK")
		)
		(pad "69" smd rect
			(at 7.750048 -5.275072 90)
			(size 0.3048 1.5494)
			(layers "F.Cu" "F.Mask" "F.Paste")
			(net "FM_M2_SSD_PEDET")
		)
		(pad "70" smd rect
			(at 7.999984 2.275078 90)
			(size 0.3048 1.5494)
			(layers "F.Cu" "F.Mask" "F.Paste")
			(net "P3V3")
		)
		(pad "71" smd rect
			(at 8.24992 -5.275072 90)
			(size 0.3048 1.5494)
			(layers "F.Cu" "F.Mask" "F.Paste")
			(net "GND")
		)
		(pad "72" smd rect
			(at 8.50011 2.275078 90)
			(size 0.3048 1.5494)
			(layers "F.Cu" "F.Mask" "F.Paste")
			(net "P3V3")
		)
		(pad "73" smd rect
			(at 8.750046 -5.275072 90)
			(size 0.3048 1.5494)
			(layers "F.Cu" "F.Mask" "F.Paste")
			(net "GND")
		)
		(pad "74" smd rect
			(at 8.999982 2.275078 90)
			(size 0.3048 1.5494)
			(layers "F.Cu" "F.Mask" "F.Paste")
			(net "P3V3")
		)
		(pad "75" smd rect
			(at 9.249918 -5.275072 90)
			(size 0.3048 1.5494)
			(layers "F.Cu" "F.Mask" "F.Paste")
			(net "GND")
		)
		(pad "76" smd rect
			(at -10.349992 -4.500118 90)
			(size 1.1938 2.7432)
			(layers "F.Cu" "F.Mask" "F.Paste")
			(net "GND")
		)
		(pad "77" smd rect
			(at 10.349992 -4.500118 90)
			(size 1.1938 2.7432)
			(layers "F.Cu" "F.Mask" "F.Paste")
			(net "GND")
		)
		(zone
			(layer "F.Cu")
			(hatch none 0.5)
			(connect_pads
				(clearance 0)
			)
			(min_thickness 0.25)
			(keepout
				(tracks allowed)
				(vias not_allowed)
				(pads allowed)
				(copperpour not_allowed)
				(footprints allowed)
			)
			(placement
				(enabled no)
				(sheetname "")
			)
			(fill
				(thermal_gap 0.5)
				(thermal_bridge_width 0.5)
				(island_removal_mode 0)
			)
			(polygon
				(pts
					(xy 383.572004 -37.618416) (xy 383.699004 -37.618416) (xy 383.699004 -39.923212) (xy 383.572004 -39.923212)
				)
			)
		)
		(zone
			(layer "F.Cu")
			(hatch none 0.5)
			(connect_pads
				(clearance 0)
			)
			(min_thickness 0.25)
			(keepout
				(tracks allowed)
				(vias not_allowed)
				(pads allowed)
				(copperpour not_allowed)
				(footprints allowed)
			)
			(placement
				(enabled no)
				(sheetname "")
			)
			(fill
				(thermal_gap 0.5)
				(thermal_bridge_width 0.5)
				(island_removal_mode 0)
			)
			(polygon
				(pts
					(xy 383.572004 -21.118576) (xy 383.699004 -21.118576) (xy 383.699004 -35.423348) (xy 383.572004 -35.423348)
				)
			)
		)
		(zone
			(layer "F.Cu")
			(hatch none 0.5)
			(connect_pads
				(clearance 0)
			)
			(min_thickness 0.25)
			(keepout
				(tracks allowed)
				(vias not_allowed)
				(pads allowed)
				(copperpour not_allowed)
				(footprints allowed)
			)
			(placement
				(enabled no)
				(sheetname "")
			)
			(fill
				(thermal_gap 0.5)
				(thermal_bridge_width 0.5)
				(island_removal_mode 0)
			)
			(polygon
				(pts
					(xy 389.445754 -37.868606) (xy 389.572754 -37.868606) (xy 389.572754 -39.673276) (xy 389.445754 -39.673276)
				)
			)
		)
		(zone
			(layer "F.Cu")
			(hatch none 0.5)
			(connect_pads
				(clearance 0)
			)
			(min_thickness 0.25)
			(keepout
				(tracks allowed)
				(vias not_allowed)
				(pads allowed)
				(copperpour not_allowed)
				(footprints allowed)
			)
			(placement
				(enabled no)
				(sheetname "")
			)
			(fill
				(thermal_gap 0.5)
				(thermal_bridge_width 0.5)
				(island_removal_mode 0)
			)
			(polygon
				(pts
					(xy 389.445754 -21.368512) (xy 389.572754 -21.368512) (xy 389.572754 -35.673284) (xy 389.445754 -35.673284)
				)
			)
		)
		(zone
			(layers "F.Cu" "B.Cu" "In1.Cu" "In2.Cu" "In3.Cu" "In4.Cu" "In5.Cu" "In6.Cu"
				"In7.Cu" "In8.Cu" "In9.Cu" "In10.Cu" "In11.Cu" "In12.Cu"
			)
			(hatch none 0.5)
			(connect_pads
				(clearance 0)
			)
			(min_thickness 0.25)
			(keepout
				(tracks not_allowed)
				(vias allowed)
				(pads allowed)
				(copperpour not_allowed)
				(footprints allowed)
			)
			(placement
				(enabled no)
				(sheetname "")
			)
			(fill
				(thermal_gap 0.5)
				(thermal_bridge_width 0.5)
				(island_removal_mode 0)
			)
			(polygon
				(pts
					(arc
						(start 388.935976 -20.520914)
						(mid 387.208776 -20.520914)
						(end 388.935976 -20.520914)
					)
				)
			)
		)
		(zone
			(layers "F.Cu" "B.Cu" "In1.Cu" "In2.Cu" "In3.Cu" "In4.Cu" "In5.Cu" "In6.Cu"
				"In7.Cu" "In8.Cu" "In9.Cu" "In10.Cu" "In11.Cu" "In12.Cu"
			)
			(hatch none 0.5)
			(connect_pads
				(clearance 0)
			)
			(min_thickness 0.25)
			(keepout
				(tracks not_allowed)
				(vias allowed)
				(pads allowed)
				(copperpour not_allowed)
				(footprints allowed)
			)
			(placement
				(enabled no)
				(sheetname "")
			)
			(fill
				(thermal_gap 0.5)
				(thermal_bridge_width 0.5)
				(island_removal_mode 0)
			)
			(polygon
				(pts
					(arc
						(start 389.177276 -40.520874)
						(mid 386.967476 -40.520874)
						(end 389.177276 -40.520874)
					)
				)
			)
		)
	)
)
